# BASEBOARD_FAB2 (Tioga Pass) — schematic netlist excerpt (pin names and nets, part order shuffled) for the footprints in the layout excerpt that follows; sources: Cadence DE-HDL packaged netlist, KiCad conversion of Wiwynn_Tioga_Pass_MB.brd

J10W1  LOTES-CON4-S1-GP  pkg CONN-G7  page 161
  \1\  = GND
  \2\  = P12V_FAN
  \3\  = FAN_TACH2_CPU1_D1
  \4\  = FAN_PWM_OUT_SYS1_R
  NP1  = NC

Q9F1  FET_N_DUAL  NTJD4001N FET  pkg SMLF  page 177
  SOURCE(0)  = GND
  GATE(0)  = FM_BMC_FAULT_LED_N
  DRAIN(0)  = FM_RED_LED_CATHODE
  SOURCE(0)  = GND
  GATE(0)  = FM_BMC_FAULT_LED
  DRAIN(0)  = FM_BMC_FAULT_LED

(kicad_pcb
	(version 20260206)
	(generator "pcbnew")
	(generator_version "10.0")
	(general
		(thickness 1.6)
		(legacy_teardrops no)
	)
	(paper "A4")
	(title_block
		(title "Wiwynn_Tioga_Pass_MB.brd")
		(comment 1 "Tioga Pass / footprints 1864-1865 of 4770")
	)
	(layers
		(0 "F.Cu" signal "TOP")
		(4 "In1.Cu" signal "L2GND")
		(6 "In2.Cu" signal "L3")
		(8 "In3.Cu" signal "L4GND")
		(10 "In4.Cu" signal "L5")
		(12 "In5.Cu" signal "L6GND")
		(14 "In6.Cu" signal "L7VCC")
		(16 "In7.Cu" signal "L8VCC")
		(18 "In8.Cu" signal "L9GND")
		(20 "In9.Cu" signal "L10")
		(22 "In10.Cu" signal "L11GND")
		(24 "In11.Cu" signal "L12")
		(26 "In12.Cu" signal "L13GND")
		(2 "B.Cu" signal "BOTTOM")
		(9 "F.Adhes" user "F.Adhesive")
		(11 "B.Adhes" user "B.Adhesive")
		(13 "F.Paste" user "Package Geometry/Pastemask Top")
		(15 "B.Paste" user "Package Geometry/Pastemask Bottom")
		(5 "F.SilkS" user "Ref Des/Silkscreen Top")
		(7 "B.SilkS" user "Ref Des/Silkscreen Bottom")
		(1 "F.Mask" user "Board Geometry/Soldermask Top")
		(3 "B.Mask" user "Board Geometry/Soldermask Bottom")
		(17 "Dwgs.User" user "User.Drawings")
		(19 "Cmts.User" user "User.Comments")
		(21 "Eco1.User" user "User.Eco1")
		(23 "Eco2.User" user "User.Eco2")
		(25 "Edge.Cuts" user "Board Geometry/Outline")
		(27 "Margin" user)
		(31 "F.CrtYd" user "Package Geometry/Place Bound Top")
		(29 "B.CrtYd" user "Package Geometry/Place Bound Bottom")
		(35 "F.Fab" user "Ref Des/Assembly Top")
		(33 "B.Fab" user "Ref Des/Assembly Bottom")
	)
	(footprint ""
		(layer "F.Cu")
		(at 456.1713 -27.432 90)
		(property "Reference" "Q9F1"
			(at 0.92202 -1.23317 90)
			(unlocked yes)
			(layer "F.SilkS")
			(effects
				(font
					(size 0.7874 0.5842)
					(thickness 0.1524)
				)
				(justify left)
			)
		)
		(property "Value" ""
			(at 0 0 90)
			(layer "F.Fab")
			(effects
				(font
					(size 1.27 1.27)
				)
			)
		)
		(duplicate_pad_numbers_are_jumpers no)
		(fp_circle
			(center -0.788416 -0.597662)
			(end -0.788416 -0.470662)
			(stroke
				(width 0.254)
				(type default)
			)
			(fill no)
			(layer "F.SilkS")
		)
		(fp_poly
			(pts
				(xy 0.2159 1.7526) (xy 1.5621 1.7526) (xy 1.5621 -0.4572) (xy 0.2159 -0.4572)
			)
			(stroke
				(width 0)
				(type default)
			)
			(fill no)
			(layer "F.CrtYd")
		)
		(fp_line
			(start 1.5621 -0.45466)
			(end 0.2159 -0.45466)
			(stroke
				(width 0.1)
				(type default)
			)
			(layer "F.Fab")
		)
		(fp_line
			(start 0.2159 -0.45466)
			(end 0.2159 1.75514)
			(stroke
				(width 0.1)
				(type default)
			)
			(layer "F.Fab")
		)
		(fp_line
			(start 1.5621 1.75514)
			(end 1.5621 -0.45466)
			(stroke
				(width 0.1)
				(type default)
			)
			(layer "F.Fab")
		)
		(fp_line
			(start 0.2159 1.75514)
			(end 1.5621 1.75514)
			(stroke
				(width 0.1)
				(type default)
			)
			(layer "F.Fab")
		)
		(fp_circle
			(center -0.508 -0.7874)
			(end -0.508 -0.6604)
			(stroke
				(width 0.254)
				(type default)
			)
			(fill no)
			(layer "F.Fab")
		)
		(pad "1" smd rect
			(at 0 0 90)
			(size 1.016 0.381)
			(layers "F.Cu" "F.Mask" "F.Paste")
			(net "GND")
		)
		(pad "2" smd rect
			(at 0 0.65024 90)
			(size 1.016 0.381)
			(layers "F.Cu" "F.Mask" "F.Paste")
			(net "FM_BMC_FAULT_LED_N")
		)
		(pad "3" smd rect
			(at 0 1.30048 90)
			(size 1.016 0.381)
			(layers "F.Cu" "F.Mask" "F.Paste")
			(net "FM_RED_LED_CATHODE")
		)
		(pad "4" smd rect
			(at 1.778 1.30048 90)
			(size 1.016 0.381)
			(layers "F.Cu" "F.Mask" "F.Paste")
			(net "GND")
		)
		(pad "5" smd rect
			(at 1.778 0.65024 90)
			(size 1.016 0.381)
			(layers "F.Cu" "F.Mask" "F.Paste")
			(net "FM_BMC_FAULT_LED")
		)
		(pad "6" smd rect
			(at 1.778 0 90)
			(size 1.016 0.381)
			(layers "F.Cu" "F.Mask" "F.Paste")
			(net "FM_BMC_FAULT_LED")
		)
		(zone
			(layer "F.Cu")
			(hatch none 0.5)
			(connect_pads
				(clearance 0)
			)
			(min_thickness 0.25)
			(keepout
				(tracks allowed)
				(vias not_allowed)
				(pads allowed)
				(copperpour not_allowed)
				(footprints allowed)
			)
			(placement
				(enabled no)
				(sheetname "")
			)
			(fill
				(thermal_gap 0.5)
				(thermal_bridge_width 0.5)
				(island_removal_mode 0)
			)
			(polygon
				(pts
					(xy 455.9808 -28.702) (xy 455.9808 -29.718) (xy 457.6699 -29.718) (xy 457.6699 -28.702)
				)
			)
		)
		(zone
			(layer "F.Cu")
			(hatch none 0.5)
			(connect_pads
				(clearance 0)
			)
			(min_thickness 0.25)
			(keepout
				(tracks allowed)
				(vias not_allowed)
				(pads allowed)
				(copperpour not_allowed)
				(footprints allowed)
			)
			(placement
				(enabled no)
				(sheetname "")
			)
			(fill
				(thermal_gap 0.5)
				(thermal_bridge_width 0.5)
				(island_removal_mode 0)
			)
			(polygon
				(pts
					(xy 455.9808 -26.924) (xy 455.9808 -27.94) (xy 457.6699 -27.94) (xy 457.6699 -26.924)
				)
			)
		)
	)
	(footprint ""
		(layer "F.Cu")
		(at 0.130048 -110.259876)
		(property "Reference" "J10W1"
			(at 0 0 0)
			(layer "F.SilkS")
			(hide yes)
			(effects
				(font
					(size 1.27 1.27)
				)
			)
		)
		(property "Value" "*"
			(at -6.3881 -0.97155 0)
			(unlocked yes)
			(layer "F.Fab")
			(hide yes)
			(effects
				(font
					(size 0.889 0.889)
					(thickness 0.1524)
				)
			)
		)
		(property "Device Type" "LOTES-CON4-S1-GP_CONN-G7-LOTESA"
			(at -6.3881 -2.49555 0)
			(unlocked yes)
			(layer "F.Fab")
			(hide yes)
			(effects
				(font
					(size 0.889 0.889)
					(thickness 0.1524)
				)
			)
		)
		(duplicate_pad_numbers_are_jumpers no)
		(fp_line
			(start -5.334 -3.302)
			(end 5.334 -3.302)
			(stroke
				(width 0.508)
				(type default)
			)
			(layer "F.SilkS")
		)
		(fp_line
			(start -5.334 -3.1242)
			(end 5.334 -3.1242)
			(stroke
				(width 0.1524)
				(type default)
			)
			(layer "F.SilkS")
		)
		(fp_line
			(start -5.334 3.0226)
			(end -5.334 -3.1242)
			(stroke
				(width 0.1524)
				(type default)
			)
			(layer "F.SilkS")
		)
		(fp_line
			(start 4.191 3.16484)
			(end 5.461 3.16484)
			(stroke
				(width 0.4064)
				(type default)
			)
			(layer "F.SilkS")
		)
		(fp_line
			(start 5.334 -3.1242)
			(end 5.334 3.0226)
			(stroke
				(width 0.1524)
				(type default)
			)
			(layer "F.SilkS")
		)
		(fp_line
			(start 5.334 3.0226)
			(end -5.334 3.0226)
			(stroke
				(width 0.1524)
				(type default)
			)
			(layer "F.SilkS")
		)
		(fp_line
			(start 5.461 3.16484)
			(end 5.461 1.89484)
			(stroke
				(width 0.4064)
				(type default)
			)
			(layer "F.SilkS")
		)
		(fp_circle
			(center -3.81 0)
			(end -2.5527 0)
			(stroke
				(width 0.3048)
				(type default)
			)
			(fill no)
			(layer "F.SilkS")
		)
		(fp_circle
			(center -1.27 0)
			(end -0.0127 0)
			(stroke
				(width 0.3048)
				(type default)
			)
			(fill no)
			(layer "F.SilkS")
		)
		(fp_circle
			(center 1.27 0)
			(end 2.5273 0)
			(stroke
				(width 0.3048)
				(type default)
			)
			(fill no)
			(layer "F.SilkS")
		)
		(fp_circle
			(center 3.81 0)
			(end 5.0673 0)
			(stroke
				(width 0.3048)
				(type default)
			)
			(fill no)
			(layer "F.SilkS")
		)
		(fp_rect
			(start -5.08 2.54)
			(end 5.08 -2.8702)
			(stroke
				(width 0)
				(type default)
			)
			(fill no)
			(layer "F.CrtYd")
		)
		(fp_poly
			(pts
				(xy -5.588 3.2766) (xy -5.588 -3.3782) (xy 5.588 -3.3782) (xy 5.588 -0.00635) (xy 5.08 -0.00635)
				(xy 5.08 -2.8702) (xy -5.08 -2.8702) (xy -5.08 2.54) (xy 5.08 2.54) (xy 5.08 0.00635) (xy 5.588 0.00635)
				(xy 5.588 3.2766)
			)
			(stroke
				(width 0)
				(type default)
			)
			(fill no)
			(layer "F.CrtYd")
		)
		(fp_rect
			(start -5.588 3.2766)
			(end 5.588 -3.3782)
			(stroke
				(width 0)
				(type default)
			)
			(fill no)
			(layer "F.Fab")
		)
		(pad "" np_thru_hole circle
			(at -1.27 2.189988)
			(size 0.254 0.254)
			(drill 1.1684)
			(layers "*.Cu" "*.Mask")
			(clearance 0.8128)
			(thermal_gap 0.8128)
		)
		(pad "1" thru_hole circle
			(at 3.81 0)
			(size 1.8034 1.8034)
			(drill 1.1684)
			(layers "*.Cu" "*.Mask")
			(remove_unused_layers no)
			(net "GND")
			(clearance 0.1905)
			(thermal_gap 0.1905)
		)
		(pad "2" thru_hole circle
			(at 1.27 0)
			(size 1.8034 1.8034)
			(drill 1.1684)
			(layers "*.Cu" "*.Mask")
			(remove_unused_layers no)
			(net "P12V_FAN")
			(clearance 0.1905)
			(thermal_gap 0.1905)
		)
		(pad "3" thru_hole circle
			(at -1.27 0)
			(size 1.8034 1.8034)
			(drill 1.1684)
			(layers "*.Cu" "*.Mask")
			(remove_unused_layers no)
			(net "FAN_TACH2_CPU1_D1")
			(clearance 0.1905)
			(thermal_gap 0.1905)
		)
		(pad "4" thru_hole circle
			(at -3.81 0)
			(size 1.8034 1.8034)
			(drill 1.1684)
			(layers "*.Cu" "*.Mask")
			(remove_unused_layers no)
			(net "FAN_PWM_OUT_SYS1_R")
			(clearance 0.1905)
			(thermal_gap 0.1905)
		)
		(zone
			(layers "F.Cu" "B.Cu" "In1.Cu" "In2.Cu" "In3.Cu" "In4.Cu" "In5.Cu" "In6.Cu"
				"In7.Cu" "In8.Cu" "In9.Cu" "In10.Cu" "In11.Cu" "In12.Cu"
			)
			(hatch none 0.5)
			(connect_pads
				(clearance 0)
			)
			(min_thickness 0.25)
			(keepout
				(tracks not_allowed)
				(vias allowed)
				(pads allowed)
				(copperpour not_allowed)
				(footprints allowed)
			)
			(placement
				(enabled no)
				(sheetname "")
			)
			(fill
				(thermal_gap 0.5)
				(thermal_bridge_width 0.5)
				(island_removal_mode 0)
			)
			(polygon
				(pts
					(arc
						(start -0.250952 -108.069888)
						(mid -2.028952 -108.069888)
						(end -0.250952 -108.069888)
					)
				)
			)
		)
	)
)
